# S9S_MB_2U (Grand Teton) — schematic netlist excerpt (pin names and nets, part order shuffled) for the footprints in the layout excerpt that follows; sources: Cadence DE-HDL packaged netlist, KiCad conversion of 03242023_DA0F0TMBIJ0_F0T_Motherboard_J_brd_V01_OCP.brd

C925  Q_CAP_DIFFBUS  DIFF BUS_0.22UF 6.3V 20% X6S  pkg C0201  page 173 : \1\ = P5E_CPU0_PE0_TX_C_DP<4> ; \2\ = P5E_CPU0_PE0_TX_DP<4>
R4732  Q_RES  4.7K 5% CHIP  pkg 0402LF  page 144 : A = P3V3_AUX ; B = PRSNT_CABLE_SWB_B2
R3476  Q_RES  33.2 1% CHIP  pkg 0402LF  page 213 : A = GPU_FPGA_THERM_OVERT_ISO_N ; B = GPU_FPGA_THERM_OVERT_ISO_R_N

(kicad_pcb
	(version 20260206)
	(generator "pcbnew")
	(generator_version "10.0")
	(general
		(thickness 1.6)
		(legacy_teardrops no)
	)
	(paper "A4")
	(title_block
		(title "03242023_DA0F0TMBIJ0_F0T_Motherboard_J_brd_V01_OCP.brd")
		(comment 1 "Grand Teton / footprints 2407-2409 of 6105")
	)
	(layers
		(0 "F.Cu" signal "TOP")
		(4 "In1.Cu" signal "GND")
		(6 "In2.Cu" signal "IN1")
		(8 "In3.Cu" signal "GND1")
		(10 "In4.Cu" signal "IN2")
		(12 "In5.Cu" signal "GND2")
		(14 "In6.Cu" signal "IN3")
		(16 "In7.Cu" signal "GND3")
		(18 "In8.Cu" signal "VCC")
		(20 "In9.Cu" signal "VCC1")
		(22 "In10.Cu" signal "GND4")
		(24 "In11.Cu" signal "IN4")
		(26 "In12.Cu" signal "GND5")
		(28 "In13.Cu" signal "IN5")
		(30 "In14.Cu" signal "GND6")
		(32 "In15.Cu" signal "IN6")
		(34 "In16.Cu" signal "GND7")
		(2 "B.Cu" signal "BOTTOM")
		(9 "F.Adhes" user "F.Adhesive")
		(11 "B.Adhes" user "B.Adhesive")
		(13 "F.Paste" user "Package Geometry/Pastemask Top")
		(15 "B.Paste" user "Package Geometry/Pastemask Bottom")
		(5 "F.SilkS" user "Ref Des/Silkscreen Top")
		(7 "B.SilkS" user "Ref Des/Silkscreen Bottom")
		(1 "F.Mask" user "Board Geometry/Soldermask Top")
		(3 "B.Mask" user "Board Geometry/Soldermask Bottom")
		(17 "Dwgs.User" user "User.Drawings")
		(19 "Cmts.User" user "User.Comments")
		(21 "Eco1.User" user "User.Eco1")
		(23 "Eco2.User" user "User.Eco2")
		(25 "Edge.Cuts" user "Board Geometry/Outline")
		(27 "Margin" user)
		(31 "F.CrtYd" user "Package Geometry/Place Bound Top")
		(29 "B.CrtYd" user "Package Geometry/Place Bound Bottom")
		(35 "F.Fab" user "Ref Des/Assembly Top")
		(33 "B.Fab" user "Ref Des/Assembly Bottom")
	)
	(footprint ""
		(layer "F.Cu")
		(at 359.7656 -404.7998 180)
		(property "Reference" "R4732"
			(at 0 0 180)
			(layer "F.SilkS")
			(hide yes)
			(effects
				(font
					(size 1.27 1.27)
				)
			)
		)
		(property "Value" ""
			(at 0 0 180)
			(layer "F.Fab")
			(effects
				(font
					(size 1.27 1.27)
				)
			)
		)
		(duplicate_pad_numbers_are_jumpers no)
		(fp_line
			(start 0.7874 0.4064)
			(end -0.7874 0.4064)
			(stroke
				(width 0.1524)
				(type default)
			)
			(layer "F.SilkS")
		)
		(fp_line
			(start 0.7874 -0.4064)
			(end 0.7874 0.4064)
			(stroke
				(width 0.1524)
				(type default)
			)
			(layer "F.SilkS")
		)
		(fp_line
			(start -0.7874 0.4064)
			(end -0.7874 -0.4064)
			(stroke
				(width 0.1524)
				(type default)
			)
			(layer "F.SilkS")
		)
		(fp_line
			(start -0.7874 -0.4064)
			(end 0.7874 -0.4064)
			(stroke
				(width 0.1524)
				(type default)
			)
			(layer "F.SilkS")
		)
		(fp_line
			(start 0.67945 0.3048)
			(end 0.120396 0.3048)
			(stroke
				(width 0.1)
				(type default)
			)
			(layer "F.Fab")
		)
		(fp_line
			(start 0.67945 -0.3048)
			(end 0.67945 0.3048)
			(stroke
				(width 0.1)
				(type default)
			)
			(layer "F.Fab")
		)
		(fp_line
			(start 0.12065 -0.2794)
			(end 0.12065 -0.3048)
			(stroke
				(width 0.1)
				(type default)
			)
			(layer "F.Fab")
		)
		(fp_line
			(start 0.12065 -0.3048)
			(end 0.67945 -0.3048)
			(stroke
				(width 0.1)
				(type default)
			)
			(layer "F.Fab")
		)
		(fp_line
			(start 0.120396 0.3048)
			(end 0.120396 0.2794)
			(stroke
				(width 0.1)
				(type default)
			)
			(layer "F.Fab")
		)
		(fp_line
			(start 0.120396 0.2794)
			(end -0.12065 0.2794)
			(stroke
				(width 0.1)
				(type default)
			)
			(layer "F.Fab")
		)
		(fp_line
			(start -0.12065 0.3048)
			(end -0.67945 0.3048)
			(stroke
				(width 0.1)
				(type default)
			)
			(layer "F.Fab")
		)
		(fp_line
			(start -0.12065 0.2794)
			(end -0.12065 0.3048)
			(stroke
				(width 0.1)
				(type default)
			)
			(layer "F.Fab")
		)
		(fp_line
			(start -0.12065 -0.2794)
			(end 0.12065 -0.2794)
			(stroke
				(width 0.1)
				(type default)
			)
			(layer "F.Fab")
		)
		(fp_line
			(start -0.12065 -0.305054)
			(end -0.12065 -0.2794)
			(stroke
				(width 0.1)
				(type default)
			)
			(layer "F.Fab")
		)
		(fp_line
			(start -0.67945 0.3048)
			(end -0.67945 -0.305054)
			(stroke
				(width 0.1)
				(type default)
			)
			(layer "F.Fab")
		)
		(fp_line
			(start -0.67945 -0.305054)
			(end -0.12065 -0.305054)
			(stroke
				(width 0.1)
				(type default)
			)
			(layer "F.Fab")
		)
		(pad "1" smd circle
			(at -0.40005 0 180)
			(size 0 0)
			(layers "F.Cu" "F.Mask" "F.Paste")
			(net "P3V3_AUX")
		)
		(pad "2" smd circle
			(at 0.40005 0 180)
			(size 0 0)
			(layers "F.Cu" "F.Mask" "F.Paste")
			(net "PRSNT_CABLE_SWB_B2")
		)
	)
	(footprint ""
		(layer "F.Cu")
		(at 160.83788 -112.232948)
		(property "Reference" "R3476"
			(at 0 0 0)
			(layer "F.SilkS")
			(hide yes)
			(effects
				(font
					(size 1.27 1.27)
				)
			)
		)
		(property "Value" ""
			(at 0 0 0)
			(layer "F.Fab")
			(effects
				(font
					(size 1.27 1.27)
				)
			)
		)
		(duplicate_pad_numbers_are_jumpers no)
		(fp_line
			(start -0.7874 -0.4064)
			(end 0.7874 -0.4064)
			(stroke
				(width 0.1524)
				(type default)
			)
			(layer "F.SilkS")
		)
		(fp_line
			(start -0.7874 0.4064)
			(end -0.7874 -0.4064)
			(stroke
				(width 0.1524)
				(type default)
			)
			(layer "F.SilkS")
		)
		(fp_line
			(start 0.7874 -0.4064)
			(end 0.7874 0.4064)
			(stroke
				(width 0.1524)
				(type default)
			)
			(layer "F.SilkS")
		)
		(fp_line
			(start 0.7874 0.4064)
			(end -0.7874 0.4064)
			(stroke
				(width 0.1524)
				(type default)
			)
			(layer "F.SilkS")
		)
		(fp_line
			(start -0.67945 -0.305054)
			(end -0.12065 -0.305054)
			(stroke
				(width 0.1)
				(type default)
			)
			(layer "F.Fab")
		)
		(fp_line
			(start -0.67945 0.3048)
			(end -0.67945 -0.305054)
			(stroke
				(width 0.1)
				(type default)
			)
			(layer "F.Fab")
		)
		(fp_line
			(start -0.12065 -0.305054)
			(end -0.12065 -0.2794)
			(stroke
				(width 0.1)
				(type default)
			)
			(layer "F.Fab")
		)
		(fp_line
			(start -0.12065 -0.2794)
			(end 0.12065 -0.2794)
			(stroke
				(width 0.1)
				(type default)
			)
			(layer "F.Fab")
		)
		(fp_line
			(start -0.12065 0.2794)
			(end -0.12065 0.3048)
			(stroke
				(width 0.1)
				(type default)
			)
			(layer "F.Fab")
		)
		(fp_line
			(start -0.12065 0.3048)
			(end -0.67945 0.3048)
			(stroke
				(width 0.1)
				(type default)
			)
			(layer "F.Fab")
		)
		(fp_line
			(start 0.120396 0.2794)
			(end -0.12065 0.2794)
			(stroke
				(width 0.1)
				(type default)
			)
			(layer "F.Fab")
		)
		(fp_line
			(start 0.120396 0.3048)
			(end 0.120396 0.2794)
			(stroke
				(width 0.1)
				(type default)
			)
			(layer "F.Fab")
		)
		(fp_line
			(start 0.12065 -0.3048)
			(end 0.67945 -0.3048)
			(stroke
				(width 0.1)
				(type default)
			)
			(layer "F.Fab")
		)
		(fp_line
			(start 0.12065 -0.2794)
			(end 0.12065 -0.3048)
			(stroke
				(width 0.1)
				(type default)
			)
			(layer "F.Fab")
		)
		(fp_line
			(start 0.67945 -0.3048)
			(end 0.67945 0.3048)
			(stroke
				(width 0.1)
				(type default)
			)
			(layer "F.Fab")
		)
		(fp_line
			(start 0.67945 0.3048)
			(end 0.120396 0.3048)
			(stroke
				(width 0.1)
				(type default)
			)
			(layer "F.Fab")
		)
		(pad "1" smd circle
			(at -0.40005 0)
			(size 0 0)
			(layers "F.Cu" "F.Mask" "F.Paste")
			(net "GPU_FPGA_THERM_OVERT_ISO_N")
		)
		(pad "2" smd circle
			(at 0.40005 0)
			(size 0 0)
			(layers "F.Cu" "F.Mask" "F.Paste")
			(net "GPU_FPGA_THERM_OVERT_ISO_R_N")
		)
	)
	(footprint ""
		(layer "F.Cu")
		(at 339.910928 -408.517344 -90)
		(property "Reference" "C925"
			(at 0 0 270)
			(layer "F.SilkS")
			(hide yes)
			(effects
				(font
					(size 1.27 1.27)
				)
			)
		)
		(property "Value" ""
			(at 0 0 270)
			(layer "F.Fab")
			(effects
				(font
					(size 1.27 1.27)
				)
			)
		)
		(duplicate_pad_numbers_are_jumpers no)
		(fp_line
			(start -0.299974 0.150114)
			(end -0.299974 -0.150114)
			(stroke
				(width 0.1)
				(type default)
			)
			(layer "F.Fab")
		)
		(fp_line
			(start 0.299974 0.150114)
			(end -0.299974 0.150114)
			(stroke
				(width 0.1)
				(type default)
			)
			(layer "F.Fab")
		)
		(fp_line
			(start -0.299974 -0.150114)
			(end 0.299974 -0.150114)
			(stroke
				(width 0.1)
				(type default)
			)
			(layer "F.Fab")
		)
		(fp_line
			(start 0.299974 -0.150114)
			(end 0.299974 0.150114)
			(stroke
				(width 0.1)
				(type default)
			)
			(layer "F.Fab")
		)
		(pad "1" smd rect
			(at -0.2667 0 270)
			(size 0.3048 0.381)
			(layers "F.Cu" "F.Mask" "F.Paste")
			(net "P5E_CPU0_PE0_TX_C_DP<4>")
		)
		(pad "2" smd rect
			(at 0.2667 0 270)
			(size 0.3048 0.381)
			(layers "F.Cu" "F.Mask" "F.Paste")
			(net "P5E_CPU0_PE0_TX_DP<4>")
		)
	)
)
